# S9S_MB_2U (Grand Teton) — schematic netlist excerpt (pin names and nets, part order shuffled) for the footprints in the layout excerpt that follows; sources: Cadence DE-HDL packaged netlist, KiCad conversion of 03242023_DA0F0TMBIJ0_F0T_Motherboard_J_brd_V01_OCP.brd

R3869  Q_RES  0 5% EMPTY  pkg 0402LF  page 156 : A = P12V_OCP_SENSE_1 ; B = P12V_OCP_SFF_ISENSE_MAM_MAM
C292  Q_CAP  22UF 4V 20% X6S  pkg C0402  page 77 : A = PVCCIN_CPU1 ; B = GND

(kicad_pcb
	(version 20260206)
	(generator "pcbnew")
	(generator_version "10.0")
	(general
		(thickness 1.6)
		(legacy_teardrops no)
	)
	(paper "A4")
	(title_block
		(title "03242023_DA0F0TMBIJ0_F0T_Motherboard_J_brd_V01_OCP.brd")
		(comment 1 "Grand Teton / footprints 3404-3405 of 6105")
	)
	(layers
		(0 "F.Cu" signal "TOP")
		(4 "In1.Cu" signal "GND")
		(6 "In2.Cu" signal "IN1")
		(8 "In3.Cu" signal "GND1")
		(10 "In4.Cu" signal "IN2")
		(12 "In5.Cu" signal "GND2")
		(14 "In6.Cu" signal "IN3")
		(16 "In7.Cu" signal "GND3")
		(18 "In8.Cu" signal "VCC")
		(20 "In9.Cu" signal "VCC1")
		(22 "In10.Cu" signal "GND4")
		(24 "In11.Cu" signal "IN4")
		(26 "In12.Cu" signal "GND5")
		(28 "In13.Cu" signal "IN5")
		(30 "In14.Cu" signal "GND6")
		(32 "In15.Cu" signal "IN6")
		(34 "In16.Cu" signal "GND7")
		(2 "B.Cu" signal "BOTTOM")
		(9 "F.Adhes" user "F.Adhesive")
		(11 "B.Adhes" user "B.Adhesive")
		(13 "F.Paste" user "Package Geometry/Pastemask Top")
		(15 "B.Paste" user "Package Geometry/Pastemask Bottom")
		(5 "F.SilkS" user "Ref Des/Silkscreen Top")
		(7 "B.SilkS" user "Ref Des/Silkscreen Bottom")
		(1 "F.Mask" user "Board Geometry/Soldermask Top")
		(3 "B.Mask" user "Board Geometry/Soldermask Bottom")
		(17 "Dwgs.User" user "User.Drawings")
		(19 "Cmts.User" user "User.Comments")
		(21 "Eco1.User" user "User.Eco1")
		(23 "Eco2.User" user "User.Eco2")
		(25 "Edge.Cuts" user "Board Geometry/Outline")
		(27 "Margin" user)
		(31 "F.CrtYd" user "Package Geometry/Place Bound Top")
		(29 "B.CrtYd" user "Package Geometry/Place Bound Bottom")
		(35 "F.Fab" user "Ref Des/Assembly Top")
		(33 "B.Fab" user "Ref Des/Assembly Bottom")
	)
	(footprint ""
		(layer "F.Cu")
		(at 435.208172 -32.173418 -90)
		(property "Reference" "R3869"
			(at 0 0 270)
			(layer "F.SilkS")
			(hide yes)
			(effects
				(font
					(size 1.27 1.27)
				)
			)
		)
		(property "Value" ""
			(at 0 0 270)
			(layer "F.Fab")
			(effects
				(font
					(size 1.27 1.27)
				)
			)
		)
		(duplicate_pad_numbers_are_jumpers no)
		(fp_line
			(start -0.7874 0.4064)
			(end -0.7874 -0.4064)
			(stroke
				(width 0.1524)
				(type default)
			)
			(layer "F.SilkS")
		)
		(fp_line
			(start 0.7874 0.4064)
			(end -0.7874 0.4064)
			(stroke
				(width 0.1524)
				(type default)
			)
			(layer "F.SilkS")
		)
		(fp_line
			(start -0.7874 -0.4064)
			(end 0.7874 -0.4064)
			(stroke
				(width 0.1524)
				(type default)
			)
			(layer "F.SilkS")
		)
		(fp_line
			(start 0.7874 -0.4064)
			(end 0.7874 0.4064)
			(stroke
				(width 0.1524)
				(type default)
			)
			(layer "F.SilkS")
		)
		(fp_line
			(start -0.67945 0.3048)
			(end -0.67945 -0.305054)
			(stroke
				(width 0.1)
				(type default)
			)
			(layer "F.Fab")
		)
		(fp_line
			(start -0.12065 0.3048)
			(end -0.67945 0.3048)
			(stroke
				(width 0.1)
				(type default)
			)
			(layer "F.Fab")
		)
		(fp_line
			(start 0.120396 0.3048)
			(end 0.120396 0.2794)
			(stroke
				(width 0.1)
				(type default)
			)
			(layer "F.Fab")
		)
		(fp_line
			(start 0.67945 0.3048)
			(end 0.120396 0.3048)
			(stroke
				(width 0.1)
				(type default)
			)
			(layer "F.Fab")
		)
		(fp_line
			(start -0.12065 0.2794)
			(end -0.12065 0.3048)
			(stroke
				(width 0.1)
				(type default)
			)
			(layer "F.Fab")
		)
		(fp_line
			(start 0.120396 0.2794)
			(end -0.12065 0.2794)
			(stroke
				(width 0.1)
				(type default)
			)
			(layer "F.Fab")
		)
		(fp_line
			(start -0.12065 -0.2794)
			(end 0.12065 -0.2794)
			(stroke
				(width 0.1)
				(type default)
			)
			(layer "F.Fab")
		)
		(fp_line
			(start 0.12065 -0.2794)
			(end 0.12065 -0.3048)
			(stroke
				(width 0.1)
				(type default)
			)
			(layer "F.Fab")
		)
		(fp_line
			(start 0.12065 -0.3048)
			(end 0.67945 -0.3048)
			(stroke
				(width 0.1)
				(type default)
			)
			(layer "F.Fab")
		)
		(fp_line
			(start 0.67945 -0.3048)
			(end 0.67945 0.3048)
			(stroke
				(width 0.1)
				(type default)
			)
			(layer "F.Fab")
		)
		(fp_line
			(start -0.67945 -0.305054)
			(end -0.12065 -0.305054)
			(stroke
				(width 0.1)
				(type default)
			)
			(layer "F.Fab")
		)
		(fp_line
			(start -0.12065 -0.305054)
			(end -0.12065 -0.2794)
			(stroke
				(width 0.1)
				(type default)
			)
			(layer "F.Fab")
		)
		(pad "1" smd rect
			(at -0.40005 0 90)
			(size 0.4572 0.508)
			(layers "F.Cu" "F.Mask" "F.Paste")
			(net "P12V_OCP_SENSE_1")
		)
		(pad "2" smd rect
			(at 0.40005 0 90)
			(size 0.4572 0.508)
			(layers "F.Cu" "F.Mask" "F.Paste")
			(net "P12V_OCP_SFF_ISENSE_MAM_MAM")
		)
	)
	(footprint ""
		(layer "F.Cu")
		(at 106.32313 -240.277142 90)
		(property "Reference" "C292"
			(at 0 0 90)
			(layer "F.SilkS")
			(hide yes)
			(effects
				(font
					(size 1.27 1.27)
				)
			)
		)
		(property "Value" ""
			(at 0 0 90)
			(layer "F.Fab")
			(effects
				(font
					(size 1.27 1.27)
				)
			)
		)
		(duplicate_pad_numbers_are_jumpers no)
		(fp_line
			(start 0.7874 -0.4064)
			(end 0.7874 0.4064)
			(stroke
				(width 0.1524)
				(type default)
			)
			(layer "F.SilkS")
		)
		(fp_line
			(start -0.7874 -0.4064)
			(end 0.7874 -0.4064)
			(stroke
				(width 0.1524)
				(type default)
			)
			(layer "F.SilkS")
		)
		(fp_line
			(start 0.7874 0.4064)
			(end -0.7874 0.4064)
			(stroke
				(width 0.1524)
				(type default)
			)
			(layer "F.SilkS")
		)
		(fp_line
			(start -0.7874 0.4064)
			(end -0.7874 -0.4064)
			(stroke
				(width 0.1524)
				(type default)
			)
			(layer "F.SilkS")
		)
		(fp_line
			(start -0.12065 -0.305054)
			(end -0.12065 -0.2794)
			(stroke
				(width 0.1)
				(type default)
			)
			(layer "F.Fab")
		)
		(fp_line
			(start -0.67945 -0.305054)
			(end -0.12065 -0.305054)
			(stroke
				(width 0.1)
				(type default)
			)
			(layer "F.Fab")
		)
		(fp_line
			(start 0.67945 -0.3048)
			(end 0.67945 0.3048)
			(stroke
				(width 0.1)
				(type default)
			)
			(layer "F.Fab")
		)
		(fp_line
			(start 0.12065 -0.3048)
			(end 0.67945 -0.3048)
			(stroke
				(width 0.1)
				(type default)
			)
			(layer "F.Fab")
		)
		(fp_line
			(start 0.12065 -0.2794)
			(end 0.12065 -0.3048)
			(stroke
				(width 0.1)
				(type default)
			)
			(layer "F.Fab")
		)
		(fp_line
			(start -0.12065 -0.2794)
			(end 0.12065 -0.2794)
			(stroke
				(width 0.1)
				(type default)
			)
			(layer "F.Fab")
		)
		(fp_line
			(start 0.120396 0.2794)
			(end -0.12065 0.2794)
			(stroke
				(width 0.1)
				(type default)
			)
			(layer "F.Fab")
		)
		(fp_line
			(start -0.12065 0.2794)
			(end -0.12065 0.3048)
			(stroke
				(width 0.1)
				(type default)
			)
			(layer "F.Fab")
		)
		(fp_line
			(start 0.67945 0.3048)
			(end 0.120396 0.3048)
			(stroke
				(width 0.1)
				(type default)
			)
			(layer "F.Fab")
		)
		(fp_line
			(start 0.120396 0.3048)
			(end 0.120396 0.2794)
			(stroke
				(width 0.1)
				(type default)
			)
			(layer "F.Fab")
		)
		(fp_line
			(start -0.12065 0.3048)
			(end -0.67945 0.3048)
			(stroke
				(width 0.1)
				(type default)
			)
			(layer "F.Fab")
		)
		(fp_line
			(start -0.67945 0.3048)
			(end -0.67945 -0.305054)
			(stroke
				(width 0.1)
				(type default)
			)
			(layer "F.Fab")
		)
		(pad "1" smd circle
			(at -0.40005 0 90)
			(size 0 0)
			(layers "F.Cu" "F.Mask" "F.Paste")
			(net "PVCCIN_CPU1")
		)
		(pad "2" smd circle
			(at 0.40005 0 90)
			(size 0 0)
			(layers "F.Cu" "F.Mask" "F.Paste")
			(net "GND")
		)
	)
)
